# T6G (Grand Teton) — schematic netlist excerpt (pin names and nets, part order shuffled) for the footprints in the layout excerpt that follows; sources: Cadence DE-HDL packaged netlist, KiCad conversion of 04192023_DAF0TMB3IC0_F0TG_MB_C_brd_V02_OCP.brd

PR447  Q_RES  1K 1% CHIP  pkg 0402LF  page 194 : A = PVDDCR_CPU0_P0 ; B = GND

Q144  MOSFET_NCH_DUAL  PJT138K IC  pkg SOT363XD  page 253
  S1  = GND
  G1  = PWRGD_PS_PWROK_PLD
  D2  = PWRGD_PS_PWROK_PLD_ISO
  S2  = GND
  G2  = PWRGD_PS_PWROK_PLD_N
  D1  = PWRGD_PS_PWROK_PLD_N

(kicad_pcb
	(version 20260206)
	(generator "pcbnew")
	(generator_version "10.0")
	(general
		(thickness 1.6)
		(legacy_teardrops no)
	)
	(paper "A4")
	(title_block
		(title "04192023_DAF0TMB3IC0_F0TG_MB_C_brd_V02_OCP.brd")
		(comment 1 "Grand Teton / footprints 5446-5447 of 8354")
	)
	(layers
		(0 "F.Cu" signal "TOP")
		(4 "In1.Cu" signal "GND")
		(6 "In2.Cu" signal "IN1")
		(8 "In3.Cu" signal "GND1")
		(10 "In4.Cu" signal "IN2")
		(12 "In5.Cu" signal "GND2")
		(14 "In6.Cu" signal "IN3")
		(16 "In7.Cu" signal "GND3")
		(18 "In8.Cu" signal "VCC")
		(20 "In9.Cu" signal "VCC1")
		(22 "In10.Cu" signal "GND4")
		(24 "In11.Cu" signal "IN4")
		(26 "In12.Cu" signal "GND5")
		(28 "In13.Cu" signal "IN5")
		(30 "In14.Cu" signal "GND6")
		(32 "In15.Cu" signal "IN6")
		(34 "In16.Cu" signal "GND7")
		(2 "B.Cu" signal "BOTTOM")
		(9 "F.Adhes" user "F.Adhesive")
		(11 "B.Adhes" user "B.Adhesive")
		(13 "F.Paste" user "Package Geometry/Pastemask Top")
		(15 "B.Paste" user "Package Geometry/Pastemask Bottom")
		(5 "F.SilkS" user "Ref Des/Silkscreen Top")
		(7 "B.SilkS" user "Ref Des/Silkscreen Bottom")
		(1 "F.Mask" user "Board Geometry/Soldermask Top")
		(3 "B.Mask" user "Board Geometry/Soldermask Bottom")
		(17 "Dwgs.User" user "User.Drawings")
		(19 "Cmts.User" user "User.Comments")
		(21 "Eco1.User" user "User.Eco1")
		(23 "Eco2.User" user "User.Eco2")
		(25 "Edge.Cuts" user "Board Geometry/Outline")
		(27 "Margin" user)
		(31 "F.CrtYd" user "Package Geometry/Place Bound Top")
		(29 "B.CrtYd" user "Package Geometry/Place Bound Bottom")
		(35 "F.Fab" user "Ref Des/Assembly Top")
		(33 "B.Fab" user "Ref Des/Assembly Bottom")
	)
	(footprint ""
		(layer "B.Cu")
		(at 314.85459 -76.889864 180)
		(property "Reference" "Q144"
			(at -1.40462 1.9939 0)
			(unlocked yes)
			(layer "B.SilkS")
			(effects
				(font
					(size 0.7874 0.5842)
					(thickness 0.1524)
				)
				(justify left mirror)
			)
		)
		(property "Value" ""
			(at 0 0 0)
			(layer "B.Fab")
			(effects
				(font
					(size 1.27 1.27)
				)
				(justify mirror)
			)
		)
		(duplicate_pad_numbers_are_jumpers no)
		(fp_line
			(start 1.332738 1.100074)
			(end 1.332738 -1.100074)
			(stroke
				(width 0.1524)
				(type default)
			)
			(layer "B.SilkS")
		)
		(fp_line
			(start 1.332738 -1.100074)
			(end 0.4826 -1.100074)
			(stroke
				(width 0.1524)
				(type default)
			)
			(layer "B.SilkS")
		)
		(fp_line
			(start 0.4826 -1.100074)
			(end 0 -0.541274)
			(stroke
				(width 0.1524)
				(type default)
			)
			(layer "B.SilkS")
		)
		(fp_line
			(start 0 -0.541274)
			(end -0.4826 -1.100074)
			(stroke
				(width 0.1524)
				(type default)
			)
			(layer "B.SilkS")
		)
		(fp_line
			(start -0.4826 -1.100074)
			(end -1.332738 -1.100074)
			(stroke
				(width 0.1524)
				(type default)
			)
			(layer "B.SilkS")
		)
		(fp_line
			(start -1.332738 1.100074)
			(end 1.332738 1.100074)
			(stroke
				(width 0.1524)
				(type default)
			)
			(layer "B.SilkS")
		)
		(fp_line
			(start -1.332738 -1.100074)
			(end -1.332738 1.100074)
			(stroke
				(width 0.1524)
				(type default)
			)
			(layer "B.SilkS")
		)
		(fp_poly
			(pts
				(xy 1.941576 -0.727202) (xy 2.643632 -1.07823) (xy 2.643632 -0.376174)
			)
			(stroke
				(width 0)
				(type default)
			)
			(fill yes)
			(layer "B.SilkS")
		)
		(fp_line
			(start 0.674878 1.100074)
			(end 0.674878 -1.100074)
			(stroke
				(width 0.1)
				(type default)
			)
			(layer "B.Fab")
		)
		(fp_line
			(start 0.674878 -1.100074)
			(end -0.674878 -1.100074)
			(stroke
				(width 0.1)
				(type default)
			)
			(layer "B.Fab")
		)
		(fp_line
			(start -0.674878 1.100074)
			(end 0.674878 1.100074)
			(stroke
				(width 0.1)
				(type default)
			)
			(layer "B.Fab")
		)
		(fp_line
			(start -0.674878 -1.100074)
			(end -0.674878 1.100074)
			(stroke
				(width 0.1)
				(type default)
			)
			(layer "B.Fab")
		)
		(fp_poly
			(pts
				(xy 2.2352 -0.298958) (xy 2.2352 -1.001014) (xy 1.533144 -0.649986)
			)
			(stroke
				(width 0)
				(type default)
			)
			(fill yes)
			(layer "B.Fab")
		)
		(pad "1" smd rect
			(at 0.94996 -0.649986 270)
			(size 0.4318 0.508)
			(layers "B.Cu" "B.Mask" "B.Paste")
			(net "GND")
		)
		(pad "2" smd rect
			(at 0.94996 0 270)
			(size 0.4318 0.508)
			(layers "B.Cu" "B.Mask" "B.Paste")
			(net "PWRGD_PS_PWROK_PLD")
		)
		(pad "3" smd rect
			(at 0.94996 0.649986 270)
			(size 0.4318 0.508)
			(layers "B.Cu" "B.Mask" "B.Paste")
			(net "PWRGD_PS_PWROK_PLD_ISO")
		)
		(pad "4" smd rect
			(at -0.94996 0.649986 270)
			(size 0.4318 0.508)
			(layers "B.Cu" "B.Mask" "B.Paste")
			(net "GND")
		)
		(pad "5" smd rect
			(at -0.94996 0 270)
			(size 0.4318 0.508)
			(layers "B.Cu" "B.Mask" "B.Paste")
			(net "PWRGD_PS_PWROK_PLD_N")
		)
		(pad "6" smd rect
			(at -0.94996 -0.649986 270)
			(size 0.4318 0.508)
			(layers "B.Cu" "B.Mask" "B.Paste")
			(net "PWRGD_PS_PWROK_PLD_N")
		)
	)
	(footprint ""
		(layer "B.Cu")
		(at 342.066118 -169.643552 90)
		(property "Reference" "PR447"
			(at 0 0 90)
			(layer "B.SilkS")
			(hide yes)
			(effects
				(font
					(size 1.27 1.27)
				)
				(justify mirror)
			)
		)
		(property "Value" ""
			(at 0 0 90)
			(layer "B.Fab")
			(effects
				(font
					(size 1.27 1.27)
				)
				(justify mirror)
			)
		)
		(duplicate_pad_numbers_are_jumpers no)
		(fp_line
			(start 0.7874 -0.4064)
			(end -0.7874 -0.4064)
			(stroke
				(width 0.1524)
				(type default)
			)
			(layer "B.SilkS")
		)
		(fp_line
			(start -0.7874 -0.4064)
			(end -0.7874 0.4064)
			(stroke
				(width 0.1524)
				(type default)
			)
			(layer "B.SilkS")
		)
		(fp_line
			(start 0.7874 0.4064)
			(end 0.7874 -0.4064)
			(stroke
				(width 0.1524)
				(type default)
			)
			(layer "B.SilkS")
		)
		(fp_line
			(start -0.7874 0.4064)
			(end 0.7874 0.4064)
			(stroke
				(width 0.1524)
				(type default)
			)
			(layer "B.SilkS")
		)
		(fp_line
			(start 0.67945 -0.305054)
			(end 0.12065 -0.305054)
			(stroke
				(width 0.1)
				(type default)
			)
			(layer "B.Fab")
		)
		(fp_line
			(start 0.12065 -0.305054)
			(end 0.12065 -0.2794)
			(stroke
				(width 0.1)
				(type default)
			)
			(layer "B.Fab")
		)
		(fp_line
			(start -0.12065 -0.3048)
			(end -0.67945 -0.3048)
			(stroke
				(width 0.1)
				(type default)
			)
			(layer "B.Fab")
		)
		(fp_line
			(start -0.67945 -0.3048)
			(end -0.67945 0.3048)
			(stroke
				(width 0.1)
				(type default)
			)
			(layer "B.Fab")
		)
		(fp_line
			(start 0.12065 -0.2794)
			(end -0.12065 -0.2794)
			(stroke
				(width 0.1)
				(type default)
			)
			(layer "B.Fab")
		)
		(fp_line
			(start -0.12065 -0.2794)
			(end -0.12065 -0.3048)
			(stroke
				(width 0.1)
				(type default)
			)
			(layer "B.Fab")
		)
		(fp_line
			(start 0.12065 0.2794)
			(end 0.12065 0.3048)
			(stroke
				(width 0.1)
				(type default)
			)
			(layer "B.Fab")
		)
		(fp_line
			(start -0.120396 0.2794)
			(end 0.12065 0.2794)
			(stroke
				(width 0.1)
				(type default)
			)
			(layer "B.Fab")
		)
		(fp_line
			(start 0.67945 0.3048)
			(end 0.67945 -0.305054)
			(stroke
				(width 0.1)
				(type default)
			)
			(layer "B.Fab")
		)
		(fp_line
			(start 0.12065 0.3048)
			(end 0.67945 0.3048)
			(stroke
				(width 0.1)
				(type default)
			)
			(layer "B.Fab")
		)
		(fp_line
			(start -0.120396 0.3048)
			(end -0.120396 0.2794)
			(stroke
				(width 0.1)
				(type default)
			)
			(layer "B.Fab")
		)
		(fp_line
			(start -0.67945 0.3048)
			(end -0.120396 0.3048)
			(stroke
				(width 0.1)
				(type default)
			)
			(layer "B.Fab")
		)
		(pad "1" smd circle
			(at 0.40005 0 270)
			(size 0 0)
			(layers "B.Cu" "B.Mask" "B.Paste")
			(net "PVDDCR_CPU0_P0")
		)
		(pad "2" smd circle
			(at -0.40005 0 270)
			(size 0 0)
			(layers "B.Cu" "B.Mask" "B.Paste")
			(net "GND")
		)
	)
)
